# T6G (Grand Teton) — schematic netlist excerpt (pin names and nets, part order shuffled) for the footprints in the layout excerpt that follows; sources: Cadence DE-HDL packaged netlist, KiCad conversion of 04192023_DAF0TMB3IC0_F0TG_MB_C_brd_V02_OCP.brd

C282  Q_CAP  0.1UF 10V 10% X7S  pkg C0201  page 323 : A = P0V9_CPU1_RT0_2A ; B = GND

J114  PICOPROBE_BXA  DELTA-L 4.0 EMPTY  pkg TRIANG_LAUNCH_3PXB  page 229
  \1_p\  = DELTA_L_85_5INCH_IN5_DP
  \2_n\  = DELTA_L_85_5INCH_IN5_DN
  \3_g\  = DELTA_L_GND_1

(kicad_pcb
	(version 20260206)
	(generator "pcbnew")
	(generator_version "10.0")
	(general
		(thickness 1.6)
		(legacy_teardrops no)
	)
	(paper "A4")
	(title_block
		(title "04192023_DAF0TMB3IC0_F0TG_MB_C_brd_V02_OCP.brd")
		(comment 1 "Grand Teton / footprints 6247-6248 of 8354")
	)
	(layers
		(0 "F.Cu" signal "TOP")
		(4 "In1.Cu" signal "GND")
		(6 "In2.Cu" signal "IN1")
		(8 "In3.Cu" signal "GND1")
		(10 "In4.Cu" signal "IN2")
		(12 "In5.Cu" signal "GND2")
		(14 "In6.Cu" signal "IN3")
		(16 "In7.Cu" signal "GND3")
		(18 "In8.Cu" signal "VCC")
		(20 "In9.Cu" signal "VCC1")
		(22 "In10.Cu" signal "GND4")
		(24 "In11.Cu" signal "IN4")
		(26 "In12.Cu" signal "GND5")
		(28 "In13.Cu" signal "IN5")
		(30 "In14.Cu" signal "GND6")
		(32 "In15.Cu" signal "IN6")
		(34 "In16.Cu" signal "GND7")
		(2 "B.Cu" signal "BOTTOM")
		(9 "F.Adhes" user "F.Adhesive")
		(11 "B.Adhes" user "B.Adhesive")
		(13 "F.Paste" user "Package Geometry/Pastemask Top")
		(15 "B.Paste" user "Package Geometry/Pastemask Bottom")
		(5 "F.SilkS" user "Ref Des/Silkscreen Top")
		(7 "B.SilkS" user "Ref Des/Silkscreen Bottom")
		(1 "F.Mask" user "Board Geometry/Soldermask Top")
		(3 "B.Mask" user "Board Geometry/Soldermask Bottom")
		(17 "Dwgs.User" user "User.Drawings")
		(19 "Cmts.User" user "User.Comments")
		(21 "Eco1.User" user "User.Eco1")
		(23 "Eco2.User" user "User.Eco2")
		(25 "Edge.Cuts" user "Board Geometry/Outline")
		(27 "Margin" user)
		(31 "F.CrtYd" user "Package Geometry/Place Bound Top")
		(29 "B.CrtYd" user "Package Geometry/Place Bound Bottom")
		(35 "F.Fab" user "Ref Des/Assembly Top")
		(33 "B.Fab" user "Ref Des/Assembly Bottom")
	)
	(footprint ""
		(layer "B.Cu")
		(at 314.965588 7.622794 180)
		(property "Reference" "J114"
			(at 4.525264 -1.200404 270)
			(unlocked yes)
			(layer "B.SilkS")
			(effects
				(font
					(size 0.7874 0.5842)
					(thickness 0.1524)
				)
				(justify left mirror)
			)
		)
		(property "Value" ""
			(at 0 0 0)
			(layer "B.Fab")
			(effects
				(font
					(size 1.27 1.27)
				)
				(justify mirror)
			)
		)
		(duplicate_pad_numbers_are_jumpers no)
		(fp_line
			(start 1.2192 2.06756)
			(end 1.2192 -2.06756)
			(stroke
				(width 0.1524)
				(type default)
			)
			(layer "B.SilkS")
		)
		(fp_line
			(start 1.2192 -2.06756)
			(end -1.2192 -2.06756)
			(stroke
				(width 0.1524)
				(type default)
			)
			(layer "B.SilkS")
		)
		(fp_line
			(start -1.2192 2.06756)
			(end 1.2192 2.06756)
			(stroke
				(width 0.1524)
				(type default)
			)
			(layer "B.SilkS")
		)
		(fp_line
			(start -1.2192 -2.06756)
			(end -1.2192 2.06756)
			(stroke
				(width 0.1524)
				(type default)
			)
			(layer "B.SilkS")
		)
		(pad "" np_thru_hole circle
			(at -3.4671 -1.27 90)
			(size 1.0414 1.0414)
			(drill 1.0414)
			(layers "*.Cu" "*.Mask")
			(clearance 0.381)
			(thermal_gap 0.381)
		)
		(pad "" np_thru_hole circle
			(at -3.4671 1.27 90)
			(size 1.0414 1.0414)
			(drill 1.0414)
			(layers "*.Cu" "*.Mask")
			(clearance 0.381)
			(thermal_gap 0.381)
		)
		(pad "" np_thru_hole circle
			(at 2.8829 -1.27 90)
			(size 1.0414 1.0414)
			(drill 1.0414)
			(layers "*.Cu" "*.Mask")
			(clearance 0.381)
			(thermal_gap 0.381)
		)
		(pad "" np_thru_hole circle
			(at 2.8829 1.27 90)
			(size 1.0414 1.0414)
			(drill 1.0414)
			(layers "*.Cu" "*.Mask")
			(clearance 0.381)
			(thermal_gap 0.381)
		)
		(pad "1" smd rect
			(at -0.8255 -0.249936 90)
			(size 0.3048 0.508)
			(layers "B.Cu" "B.Mask" "B.Paste")
			(net "DELTA_L_85_5INCH_IN5_DP")
		)
		(pad "2" smd rect
			(at -0.8255 0.249936 90)
			(size 0.3048 0.508)
			(layers "B.Cu" "B.Mask" "B.Paste")
			(net "DELTA_L_85_5INCH_IN5_DN")
		)
		(pad "3" smd circle
			(at 0 0)
			(size 0 0)
			(layers "B.Cu" "B.Mask" "B.Paste")
			(net "DELTA_L_GND_1")
		)
		(zone
			(layers "F.Cu" "B.Cu" "In1.Cu" "In2.Cu" "In3.Cu" "In4.Cu" "In5.Cu" "In6.Cu"
				"In7.Cu" "In8.Cu" "In9.Cu" "In10.Cu" "In11.Cu" "In12.Cu" "In13.Cu" "In14.Cu"
				"In15.Cu" "In16.Cu"
			)
			(hatch none 0.5)
			(connect_pads
				(clearance 0)
			)
			(min_thickness 0.25)
			(keepout
				(tracks not_allowed)
				(vias allowed)
				(pads allowed)
				(copperpour not_allowed)
				(footprints allowed)
			)
			(placement
				(enabled no)
				(sheetname "")
			)
			(fill
				(thermal_gap 0.5)
				(thermal_bridge_width 0.5)
				(island_removal_mode 0)
			)
			(polygon
				(pts
					(arc
						(start 313.009788 6.352794)
						(mid 311.155588 6.352794)
						(end 313.009788 6.352794)
					)
				)
			)
		)
		(zone
			(layers "F.Cu" "B.Cu" "In1.Cu" "In2.Cu" "In3.Cu" "In4.Cu" "In5.Cu" "In6.Cu"
				"In7.Cu" "In8.Cu" "In9.Cu" "In10.Cu" "In11.Cu" "In12.Cu" "In13.Cu" "In14.Cu"
				"In15.Cu" "In16.Cu"
			)
			(hatch none 0.5)
			(connect_pads
				(clearance 0)
			)
			(min_thickness 0.25)
			(keepout
				(tracks not_allowed)
				(vias allowed)
				(pads allowed)
				(copperpour not_allowed)
				(footprints allowed)
			)
			(placement
				(enabled no)
				(sheetname "")
			)
			(fill
				(thermal_gap 0.5)
				(thermal_bridge_width 0.5)
				(island_removal_mode 0)
			)
			(polygon
				(pts
					(arc
						(start 313.009788 8.892794)
						(mid 311.155588 8.892794)
						(end 313.009788 8.892794)
					)
				)
			)
		)
		(zone
			(layers "F.Cu" "B.Cu" "In1.Cu" "In2.Cu" "In3.Cu" "In4.Cu" "In5.Cu" "In6.Cu"
				"In7.Cu" "In8.Cu" "In9.Cu" "In10.Cu" "In11.Cu" "In12.Cu" "In13.Cu" "In14.Cu"
				"In15.Cu" "In16.Cu"
			)
			(hatch none 0.5)
			(connect_pads
				(clearance 0)
			)
			(min_thickness 0.25)
			(keepout
				(tracks not_allowed)
				(vias allowed)
				(pads allowed)
				(copperpour not_allowed)
				(footprints allowed)
			)
			(placement
				(enabled no)
				(sheetname "")
			)
			(fill
				(thermal_gap 0.5)
				(thermal_bridge_width 0.5)
				(island_removal_mode 0)
			)
			(polygon
				(pts
					(arc
						(start 319.359788 6.352794)
						(mid 317.505588 6.352794)
						(end 319.359788 6.352794)
					)
				)
			)
		)
		(zone
			(layers "F.Cu" "B.Cu" "In1.Cu" "In2.Cu" "In3.Cu" "In4.Cu" "In5.Cu" "In6.Cu"
				"In7.Cu" "In8.Cu" "In9.Cu" "In10.Cu" "In11.Cu" "In12.Cu" "In13.Cu" "In14.Cu"
				"In15.Cu" "In16.Cu"
			)
			(hatch none 0.5)
			(connect_pads
				(clearance 0)
			)
			(min_thickness 0.25)
			(keepout
				(tracks not_allowed)
				(vias allowed)
				(pads allowed)
				(copperpour not_allowed)
				(footprints allowed)
			)
			(placement
				(enabled no)
				(sheetname "")
			)
			(fill
				(thermal_gap 0.5)
				(thermal_bridge_width 0.5)
				(island_removal_mode 0)
			)
			(polygon
				(pts
					(arc
						(start 319.359788 8.892794)
						(mid 317.505588 8.892794)
						(end 319.359788 8.892794)
					)
				)
			)
		)
		(zone
			(layer "B.Cu")
			(hatch none 0.5)
			(connect_pads
				(clearance 0)
			)
			(min_thickness 0.25)
			(keepout
				(tracks not_allowed)
				(vias allowed)
				(pads allowed)
				(copperpour not_allowed)
				(footprints allowed)
			)
			(placement
				(enabled no)
				(sheetname "")
			)
			(fill
				(thermal_gap 0.5)
				(thermal_bridge_width 0.5)
				(island_removal_mode 0)
			)
			(polygon
				(pts
					(xy 316.083188 8.171434) (xy 316.083188 8.07593) (xy 315.486288 8.07593) (xy 315.486288 7.66953)
					(xy 316.083188 7.66953) (xy 316.083188 7.576058) (xy 315.486288 7.576058) (xy 315.486288 7.169658)
					(xy 316.083188 7.169658) (xy 316.083188 7.074154) (xy 315.384688 7.074154) (xy 315.384688 8.171434)
				)
			)
		)
	)
	(footprint ""
		(layer "B.Cu")
		(at 47.518574 -388.011162 -90)
		(property "Reference" "C282"
			(at 0 0 90)
			(layer "B.SilkS")
			(hide yes)
			(effects
				(font
					(size 1.27 1.27)
				)
				(justify mirror)
			)
		)
		(property "Value" ""
			(at 0 0 90)
			(layer "B.Fab")
			(effects
				(font
					(size 1.27 1.27)
				)
				(justify mirror)
			)
		)
		(duplicate_pad_numbers_are_jumpers no)
		(fp_line
			(start -0.299974 0.150114)
			(end 0.299974 0.150114)
			(stroke
				(width 0.1)
				(type default)
			)
			(layer "B.Fab")
		)
		(fp_line
			(start 0.299974 0.150114)
			(end 0.299974 -0.150114)
			(stroke
				(width 0.1)
				(type default)
			)
			(layer "B.Fab")
		)
		(fp_line
			(start -0.299974 -0.150114)
			(end -0.299974 0.150114)
			(stroke
				(width 0.1)
				(type default)
			)
			(layer "B.Fab")
		)
		(fp_line
			(start 0.299974 -0.150114)
			(end -0.299974 -0.150114)
			(stroke
				(width 0.1)
				(type default)
			)
			(layer "B.Fab")
		)
		(pad "1" smd rect
			(at 0.2667 0 90)
			(size 0.3048 0.381)
			(layers "B.Cu" "B.Mask" "B.Paste")
			(net "P0V9_CPU1_RT0_2A")
		)
		(pad "2" smd rect
			(at -0.2667 0 90)
			(size 0.3048 0.381)
			(layers "B.Cu" "B.Mask" "B.Paste")
			(net "GND")
		)
	)
)
